
Section 2 - Conflicts on Net Synonyms
--------------------------------------

DRAWING = @BASEBOARD_FAB2_LIB.BASEBOARD_FAB2(SCH_1)
NET_NAME = P5V_STBY
   OPF: VOLTAGE = +5.0V; NET = P5V_STBY
   OPF: VOLTAGE = +5.0V; NET = P5V_STBY
   OPF: VOLTAGE = +5.0V; NET = P5V_STBY
   OPF: VOLTAGE = +5; NET = P5V_STBY
 * SCH: VOLTAGE = 5.0V
NET_NAME = PVCCIOMCP_CPU1
   OPF: VOLTAGE = +0.95; NET = PVCCIOMCP_CPU1
 * SCH: VOLTAGE = +0.95V
NET_NAME = P5V
   OPF: VOLTAGE = +5.0V; NET = P5V
   OPF: VOLTAGE = +5.0V; NET = P5V
 * SCH: VOLTAGE = 5.0V
NET_NAME = P12V
   OPF: VOLTAGE = 12.0V; NET = P12V
   OPF: VOLTAGE = 12.0V; NET = P12V
   OPF: VOLTAGE = +12.0V; NET = P12V
 * SCH: VOLTAGE = +12.
NET_NAME = P3V3
   OPF: VOLTAGE = +3.3; NET = P3V3
   OPF: VOLTAGE = +3.3; NET = P3V3
   OPF: VOLTAGE = +3.3; NET = P3V3
   OPF: VOLTAGE = +3.3V; NET = P3V3
   OPF: VOLTAGE = +3.3V; NET = P3V3
   OPF: VOLTAGE = +3.3V; NET = P3V3
 * SCH: VOLTAGE = 3.3V
NET_NAME = P3V3_STBY
   OPF: VOLTAGE = 3.3; NET = P3V3_STBY
   OPF: VOLTAGE = +3.3V; NET = P3V3_STBY
   OPF: VOLTAGE = +3.3V; NET = P3V3_STBY
   OPF: VOLTAGE = +3.3V; NET = P3V3_STBY
   OPF: VOLTAGE = +3.3V; NET = P3V3_STBY
   OPF: VOLTAGE = +3.3V; NET = P3V3_STBY
   OPF: VOLTAGE = +3.3V; NET = P3V3_STBY
   OPF: VOLTAGE = +3.3V; NET = P3V3_STBY
   OPF: VOLTAGE = +3.3V; NET = P3V3_STBY
   OPF: VOLTAGE = +3.3V; NET = P3V3_STBY
 * SCH: VOLTAGE = 3.3V
NET_NAME = GND
   OPF: VOLTAGE = 0; NET = GND
   OPF: VOLTAGE = 0; NET = GND
   OPF: VOLTAGE = 0; NET = GND
   OPF: VOLTAGE = 0; NET = GND
   OPF: VOLTAGE = 0; NET = GND
   OPF: VOLTAGE = 0; NET = GND
   OPF: VOLTAGE = 0; NET = GND
   OPF: VOLTAGE = 0; NET = GND
   OPF: VOLTAGE = 0; NET = GND
   OPF: VOLTAGE = 0; NET = GND
   OPF: VOLTAGE = 0; NET = GND
   OPF: VOLTAGE = 0; NET = GND
   OPF: VOLTAGE = 0; NET = GND
   OPF: VOLTAGE = 0; NET = GND
   OPF: VOLTAGE = 0; NET = GND
   OPF: VOLTAGE = 0; NET = GND
   OPF: VOLTAGE = 0; NET = GND
   OPF: VOLTAGE = 0; NET = GND
   OPF: VOLTAGE = 0; NET = GND
   OPF: VOLTAGE = 0; NET = GND
   OPF: VOLTAGE = 0; NET = GND
   OPF: VOLTAGE = 0; NET = GND
   OPF: VOLTAGE = 0; NET = GND
   OPF: VOLTAGE = 0; NET = GND
   OPF: VOLTAGE = 0; NET = GND
   OPF: VOLTAGE = 0; NET = GND
   OPF: VOLTAGE = 0; NET = GND
   OPF: VOLTAGE = 0; NET = GND
   OPF: VOLTAGE = 0; NET = GND
   OPF: VOLTAGE = 0; NET = GND
   OPF: VOLTAGE = 0; NET = GND
   OPF: VOLTAGE = 0; NET = GND
   OPF: VOLTAGE = 0; NET = GND
   OPF: VOLTAGE = 0; NET = GND
   OPF: VOLTAGE = 0; NET = GND
   OPF: VOLTAGE = 0; NET = GND
   OPF: VOLTAGE = 0; NET = GND
   OPF: VOLTAGE = 0; NET = GND
   OPF: VOLTAGE = 0; NET = GND
   OPF: VOLTAGE = 0; NET = GND
   OPF: VOLTAGE = 0; NET = GND
   OPF: VOLTAGE = 0; NET = GND
   OPF: VOLTAGE = 0; NET = GND
   OPF: VOLTAGE = 0; NET = GND
   OPF: VOLTAGE = 0; NET = GND
   OPF: VOLTAGE = 0; NET = GND
   OPF: VOLTAGE = 0; NET = GND
   OPF: VOLTAGE = 0; NET = GND
   OPF: VOLTAGE = 0; NET = GND
   OPF: VOLTAGE = 0; NET = GND
   OPF: VOLTAGE = 0; NET = GND
   OPF: VOLTAGE = 0; NET = GND
   OPF: VOLTAGE = 0; NET = GND
   OPF: VOLTAGE = 0; NET = GND
   OPF: VOLTAGE = 0; NET = GND
   OPF: VOLTAGE = 0; NET = GND
   OPF: VOLTAGE = 0; NET = GND
   OPF: VOLTAGE = 0; NET = GND
   OPF: VOLTAGE = 0; NET = GND
   OPF: VOLTAGE = 0; NET = GND
   OPF: VOLTAGE = 0; NET = GND
   OPF: VOLTAGE = 0; NET = GND
   OPF: VOLTAGE = 0; NET = GND
   OPF: VOLTAGE = 0; NET = GND
   OPF: VOLTAGE = 0; NET = GND
   OPF: VOLTAGE = 0; NET = GND
   OPF: VOLTAGE = 0; NET = GND
   OPF: VOLTAGE = 0; NET = GND
   OPF: VOLTAGE = 0; NET = GND
   OPF: VOLTAGE = 0; NET = GND
   OPF: VOLTAGE = 0; NET = GND
   OPF: VOLTAGE = 0; NET = GND
   OPF: VOLTAGE = 0; NET = GND
   OPF: VOLTAGE = 0; NET = GND
   OPF: VOLTAGE = 0; NET = GND
   OPF: VOLTAGE = 0; NET = GND
   OPF: VOLTAGE = 0; NET = GND
   OPF: VOLTAGE = 0; NET = GND
   OPF: VOLTAGE = 0; NET = GND
   OPF: VOLTAGE = 0; NET = GND
   OPF: VOLTAGE = 0; NET = GND
   OPF: VOLTAGE = 0; NET = GND
   OPF: VOLTAGE = 0; NET = GND
   OPF: VOLTAGE = 0; NET = GND
   OPF: VOLTAGE = 0; NET = GND
   OPF: VOLTAGE = 0; NET = GND
   OPF: VOLTAGE = 0; NET = GND
   OPF: VOLTAGE = 0; NET = GND
   OPF: VOLTAGE = 0; NET = GND
   OPF: VOLTAGE = 0; NET = GND
   OPF: VOLTAGE = 0; NET = GND
 * SCH: VOLTAGE = 0.0V

Logical and Physical Net Conflicts 
----------------------------------

DRAWING = @BASEBOARD_FAB2_LIB.BASEBOARD_FAB2(SCH_1)
NET_NAME = FM_PCH_BMC_THERMTRIP_EXI_STRAP_N
   PNN = FM_PCH_BMC_THERMTRIP_EXI_STRAP_
NET_NAME = TP_JUMPER_BLOCK_ 1_7
   PNN = TP_JUMPER_BLOCK_1_7
NET_NAME = FM_FAST_PROCHOT_THROTTLE_DLY_BUF_N
   PNN = FM_FAST_PROCHOT_THROTTLE_DLY_BU
NET_NAME = PU_VR_PVCCIN_CPU0_FLT1_SMBALT_N_IMON
   PNN = PU_VR_PVCCIN_CPU0_FLT1_SMBALT_N
NET_NAME = PU_VR_PVCCIN_CPU1_FLT1_SMBALT_N_IMON
   PNN = PU_VR_PVCCIN_CPU1_FLT1_SMBALT_N
